FILE_TYPE = MACRO_DRAWING;
SET COLOR_WIRE YELLOW;
SET COLOR_PROP ORANGE;
SET COLOR_DOT WHITE;
SET COLOR_ARC YELLOW;
SET COLOR_BODY GREEN;
SET COLOR_NOTE PURPLE;
SET PROP_DISPLAY VALUE;
SET PAGE_NUMBER P19;
SET PATH_NUMBER P0;
FORCEADD QUANTA_TITLE_BLOCK_C..1
(5325 -2025);
FORCEPROP 0 LAST CDS_CON_LAST_MODIFIED Fri Aug 25 17:25:39 2023
J 0
(3440 -2010);
DISPLAY INVISIBLE (3440 -2010);
FORCEPROP 2 LAST Q_DEPT 
J 1
(1562 -1976);
DISPLAY 1.957447 (1562 -1976);
PAINT GREEN (1562 -1976);
FORCEPROP 2 LAST CUSTOM_TXT_CDS <XR_PAGE_TITLE>
J 0
(-2565 3225);
DISPLAY 0.638298 (-2565 3225);
PAINT PINK (-2565 3225);
DISPLAY INVISIBLE (-2565 3225);
FORCEPROP 2 LAST CUSTOM_TXT_CDS <CON_LAST_MODIFIED>
J 0
(3440 -2010);
DISPLAY 0.978723 (3440 -2010);
FORCEPROP 2 LAST CUSTOM_TXT_CDS <Q_REV>
J 0
(5141 -1922);
FORCEPROP 2 LAST CUSTOM_TXT_CDS <Q_NUMBER>
J 0
(3922 -1922);
DISPLAY 1.212766 (3922 -1922);
FORCEPROP 2 LAST CUSTOM_TXT_CDS <CON_PAGE_NUM> OF <CON_TOTAL_PAGES>
J 0
(4879 -2007);
DISPLAY 0.978723 (4879 -2007);
FORCEPROP 2 LAST CUSTOM_TXT_CDS <Q_PROJ>
J 0
(2943 -1923);
DISPLAY 1.212766 (2943 -1923);
FORCEPROP 1 LAST CUSTOM_TXT_CDS <NAME_2>
J 0
(2150 -1975);
FORCEPROP 1 LAST CUSTOM_TXT_CDS <NAME_1>
J 0
(2150 -1850);
FORCEPROP 1 LAST Q_TITLE BMC_PHY_BCM54612E 2/2
J 0
(-3991 -1924);
DISPLAY 2.446809 (-3991 -1924);
PAINT GREEN (-3991 -1924);
FORCEPROP 2 LAST CDS_LIB pure_quanta
J 0
(5325 -2025);
DISPLAY INVISIBLE (5325 -2025);
FORCEPROP 1 LAST CDS_LMAN_SYM_OUTLINE -9475,6775,100,-125
J 0
(5325 -2025);
DISPLAY 0.468085 (5325 -2025);
PAINT GREEN (5325 -2025);
DISPLAY INVISIBLE (5325 -2025);
FORCEPROP 2 LAST PAGE_BORDER TRUE
J 0
(-2565 3225);
DISPLAY 0.638298 (-2565 3225);
PAINT PINK (-2565 3225);
DISPLAY INVISIBLE (-2565 3225);
FORCEPROP 1 LAST COMMENT_BODY TRUE
J 0
(5337 -2038);
DISPLAY 0.978723 (5337 -2038);
PAINT PEACH (5337 -2038);
DISPLAY INVISIBLE (5337 -2038);
FORCEPROP 2 LAST CDS_XR_PAGE_TITLE CR-19 : @SCM_LIB.SCM(SCH_1):PAGE19
J 0
(-2565 3225);
DISPLAY 0.638298 (-2565 3225);
PAINT PINK (-2565 3225);
DISPLAY INVISIBLE (-2565 3225);
QUIT
